(kicad_pcb
	(version 20260206)
	(generator "pcbnew")
	(generator_version "10.0")
	(general
		(thickness 1.6)
		(legacy_teardrops no)
	)
	(paper "A4")
	(title_block
		(title "Wiwynn_Tioga_Pass_MB.brd")
		(comment 1 "Tioga Pass / footprints 3706-3713 of 4770")
	)
	(layers
		(0 "F.Cu" signal "TOP")
		(4 "In1.Cu" signal "L2GND")
		(6 "In2.Cu" signal "L3")
		(8 "In3.Cu" signal "L4GND")
		(10 "In4.Cu" signal "L5")
		(12 "In5.Cu" signal "L6GND")
		(14 "In6.Cu" signal "L7VCC")
		(16 "In7.Cu" signal "L8VCC")
		(18 "In8.Cu" signal "L9GND")
		(20 "In9.Cu" signal "L10")
		(22 "In10.Cu" signal "L11GND")
		(24 "In11.Cu" signal "L12")
		(26 "In12.Cu" signal "L13GND")
		(2 "B.Cu" signal "BOTTOM")
		(9 "F.Adhes" user "F.Adhesive")
		(11 "B.Adhes" user "B.Adhesive")
		(13 "F.Paste" user "Package Geometry/Pastemask Top")
		(15 "B.Paste" user "Package Geometry/Pastemask Bottom")
		(5 "F.SilkS" user "Ref Des/Silkscreen Top")
		(7 "B.SilkS" user "Ref Des/Silkscreen Bottom")
		(1 "F.Mask" user "Board Geometry/Soldermask Top")
		(3 "B.Mask" user "Board Geometry/Soldermask Bottom")
		(17 "Dwgs.User" user "User.Drawings")
		(19 "Cmts.User" user "User.Comments")
		(21 "Eco1.User" user "User.Eco1")
		(23 "Eco2.User" user "User.Eco2")
		(25 "Edge.Cuts" user "Board Geometry/Outline")
		(27 "Margin" user)
		(31 "F.CrtYd" user "Package Geometry/Place Bound Top")
		(29 "B.CrtYd" user "Package Geometry/Place Bound Bottom")
		(35 "F.Fab" user "Ref Des/Assembly Top")
		(33 "B.Fab" user "Ref Des/Assembly Bottom")
	)
	(footprint ""
		(layer "B.Cu")
		(at 111.000032 -12.954 90)
		(property "Reference" "C5G96"
			(at -1.14681 0.76708 180)
			(unlocked yes)
			(layer "B.SilkS")
			(effects
				(font
					(size 0.7874 0.5842)
					(thickness 0.1524)
				)
				(justify mirror)
			)
		)
		(property "Value" ""
			(at 0 0 90)
			(layer "B.Fab")
			(effects
				(font
					(size 1.27 1.27)
				)
				(justify mirror)
			)
		)
		(duplicate_pad_numbers_are_jumpers no)
		(fp_rect
			(start -0.4953 -0.2032)
			(end 0.4953 1.6002)
			(stroke
				(width 0)
				(type default)
			)
			(fill no)
			(layer "B.CrtYd")
		)
		(fp_line
			(start 0.4953 -0.2032)
			(end -0.4953 -0.2032)
			(stroke
				(width 0.1)
				(type default)
			)
			(layer "B.Fab")
		)
		(fp_line
			(start -0.4953 -0.2032)
			(end -0.4953 1.6002)
			(stroke
				(width 0.1)
				(type default)
			)
			(layer "B.Fab")
		)
		(fp_line
			(start 0.4953 1.6002)
			(end 0.4953 -0.2032)
			(stroke
				(width 0.1)
				(type default)
			)
			(layer "B.Fab")
		)
		(fp_line
			(start -0.4953 1.6002)
			(end 0.4953 1.6002)
			(stroke
				(width 0.1)
				(type default)
			)
			(layer "B.Fab")
		)
		(pad "1" smd rect
			(at 0 0 270)
			(size 0.762 0.889)
			(layers "B.Cu" "B.Mask" "B.Paste")
			(net "PVDDQ_GHJ")
		)
		(pad "2" smd rect
			(at 0 1.397 270)
			(size 0.762 0.889)
			(layers "B.Cu" "B.Mask" "B.Paste")
			(net "GND")
		)
		(zone
			(layer "B.Cu")
			(hatch none 0.5)
			(connect_pads
				(clearance 0)
			)
			(min_thickness 0.25)
			(keepout
				(tracks not_allowed)
				(vias allowed)
				(pads allowed)
				(copperpour not_allowed)
				(footprints allowed)
			)
			(placement
				(enabled no)
				(sheetname "")
			)
			(fill
				(thermal_gap 0.5)
				(thermal_bridge_width 0.5)
				(island_removal_mode 0)
			)
			(polygon
				(pts
					(xy 111.444532 -12.573) (xy 111.952532 -12.573) (xy 111.952532 -13.335) (xy 111.444532 -13.335)
				)
			)
		)
	)
	(footprint ""
		(layer "B.Cu")
		(at 465.641944 -7.48792 180)
		(property "Reference" "C2U21"
			(at 0 0 0)
			(layer "B.SilkS")
			(hide yes)
			(effects
				(font
					(size 1.27 1.27)
				)
				(justify mirror)
			)
		)
		(property "Value" ""
			(at 0 0 0)
			(layer "B.Fab")
			(effects
				(font
					(size 1.27 1.27)
				)
				(justify mirror)
			)
		)
		(duplicate_pad_numbers_are_jumpers no)
		(fp_poly
			(pts
				(xy -0.3048 -0.1016) (xy -0.3048 0.9906) (xy 0.3048 0.9906) (xy 0.3048 -0.1016)
			)
			(stroke
				(width 0)
				(type default)
			)
			(fill no)
			(layer "B.CrtYd")
		)
		(fp_line
			(start 0.3048 0.9906)
			(end -0.3048 0.9906)
			(stroke
				(width 0.1)
				(type default)
			)
			(layer "B.Fab")
		)
		(fp_line
			(start 0.3048 -0.1016)
			(end 0.3048 0.9906)
			(stroke
				(width 0.1)
				(type default)
			)
			(layer "B.Fab")
		)
		(fp_line
			(start -0.3048 0.9906)
			(end -0.3048 -0.1016)
			(stroke
				(width 0.1)
				(type default)
			)
			(layer "B.Fab")
		)
		(fp_line
			(start -0.3048 -0.1016)
			(end 0.3048 -0.1016)
			(stroke
				(width 0.1)
				(type default)
			)
			(layer "B.Fab")
		)
		(pad "1" smd rect
			(at 0 0)
			(size 0.508 0.508)
			(layers "B.Cu" "B.Mask" "B.Paste")
			(net "P3V3")
		)
		(pad "2" smd rect
			(at 0 0.889)
			(size 0.508 0.508)
			(layers "B.Cu" "B.Mask" "B.Paste")
			(net "GND")
		)
		(zone
			(layer "B.Cu")
			(hatch none 0.5)
			(connect_pads
				(clearance 0)
			)
			(min_thickness 0.25)
			(keepout
				(tracks not_allowed)
				(vias allowed)
				(pads allowed)
				(copperpour not_allowed)
				(footprints allowed)
			)
			(placement
				(enabled no)
				(sheetname "")
			)
			(fill
				(thermal_gap 0.5)
				(thermal_bridge_width 0.5)
				(island_removal_mode 0)
			)
			(polygon
				(pts
					(xy 465.387944 -8.12292) (xy 465.895944 -8.12292) (xy 465.895944 -7.74192) (xy 465.387944 -7.74192)
				)
			)
		)
		(zone
			(layer "B.Cu")
			(hatch none 0.5)
			(connect_pads
				(clearance 0)
			)
			(min_thickness 0.25)
			(keepout
				(tracks allowed)
				(vias not_allowed)
				(pads allowed)
				(copperpour not_allowed)
				(footprints allowed)
			)
			(placement
				(enabled no)
				(sheetname "")
			)
			(fill
				(thermal_gap 0.5)
				(thermal_bridge_width 0.5)
				(island_removal_mode 0)
			)
			(polygon
				(pts
					(xy 465.387944 -7.74192) (xy 465.895944 -7.74192) (xy 465.895944 -8.12292) (xy 465.387944 -8.12292)
				)
			)
		)
	)
	(footprint ""
		(layer "B.Cu")
		(at 464.82 -12.319 90)
		(property "Reference" "C2T7"
			(at 0 0 90)
			(layer "B.SilkS")
			(hide yes)
			(effects
				(font
					(size 1.27 1.27)
				)
				(justify mirror)
			)
		)
		(property "Value" ""
			(at 0 0 90)
			(layer "B.Fab")
			(effects
				(font
					(size 1.27 1.27)
				)
				(justify mirror)
			)
		)
		(duplicate_pad_numbers_are_jumpers no)
		(fp_rect
			(start 0.7239 -0.2159)
			(end -0.7239 1.9939)
			(stroke
				(width 0)
				(type default)
			)
			(fill no)
			(layer "B.CrtYd")
		)
		(fp_line
			(start 0.7239 -0.2159)
			(end 0.7239 1.9939)
			(stroke
				(width 0.1)
				(type default)
			)
			(layer "B.Fab")
		)
		(fp_line
			(start -0.7239 -0.2159)
			(end 0.7239 -0.2159)
			(stroke
				(width 0.1)
				(type default)
			)
			(layer "B.Fab")
		)
		(fp_line
			(start 0.7239 1.9939)
			(end -0.7239 1.9939)
			(stroke
				(width 0.1)
				(type default)
			)
			(layer "B.Fab")
		)
		(fp_line
			(start -0.7239 1.9939)
			(end -0.7239 -0.2159)
			(stroke
				(width 0.1)
				(type default)
			)
			(layer "B.Fab")
		)
		(pad "1" smd rect
			(at 0 0 270)
			(size 1.27 1.016)
			(layers "B.Cu" "B.Mask" "B.Paste")
			(net "P3V3_STBY")
		)
		(pad "2" smd rect
			(at 0 1.778 270)
			(size 1.27 1.016)
			(layers "B.Cu" "B.Mask" "B.Paste")
			(net "GND")
		)
		(zone
			(layer "B.Cu")
			(hatch none 0.5)
			(connect_pads
				(clearance 0)
			)
			(min_thickness 0.25)
			(keepout
				(tracks not_allowed)
				(vias allowed)
				(pads allowed)
				(copperpour not_allowed)
				(footprints allowed)
			)
			(placement
				(enabled no)
				(sheetname "")
			)
			(fill
				(thermal_gap 0.5)
				(thermal_bridge_width 0.5)
				(island_removal_mode 0)
			)
			(polygon
				(pts
					(xy 465.328 -12.954) (xy 465.328 -11.684) (xy 466.09 -11.684) (xy 466.09 -12.954)
				)
			)
		)
	)
	(footprint ""
		(layer "B.Cu")
		(at 421.513 -141.9606)
		(property "Reference" "C2L44"
			(at 0 0 0)
			(layer "B.SilkS")
			(hide yes)
			(effects
				(font
					(size 1.27 1.27)
				)
				(justify mirror)
			)
		)
		(property "Value" ""
			(at 0 0 0)
			(layer "B.Fab")
			(effects
				(font
					(size 1.27 1.27)
				)
				(justify mirror)
			)
		)
		(duplicate_pad_numbers_are_jumpers no)
		(fp_poly
			(pts
				(xy -0.3048 -0.1016) (xy -0.3048 0.9906) (xy 0.3048 0.9906) (xy 0.3048 -0.1016)
			)
			(stroke
				(width 0)
				(type default)
			)
			(fill no)
			(layer "B.CrtYd")
		)
		(fp_line
			(start -0.3048 -0.1016)
			(end 0.3048 -0.1016)
			(stroke
				(width 0.1)
				(type default)
			)
			(layer "B.Fab")
		)
		(fp_line
			(start -0.3048 0.9906)
			(end -0.3048 -0.1016)
			(stroke
				(width 0.1)
				(type default)
			)
			(layer "B.Fab")
		)
		(fp_line
			(start 0.3048 -0.1016)
			(end 0.3048 0.9906)
			(stroke
				(width 0.1)
				(type default)
			)
			(layer "B.Fab")
		)
		(fp_line
			(start 0.3048 0.9906)
			(end -0.3048 0.9906)
			(stroke
				(width 0.1)
				(type default)
			)
			(layer "B.Fab")
		)
		(pad "1" smd rect
			(at 0 0 180)
			(size 0.508 0.508)
			(layers "B.Cu" "B.Mask" "B.Paste")
			(net "SATA6G_P1_TX_C_DN")
		)
		(pad "2" smd rect
			(at 0 0.889 180)
			(size 0.508 0.508)
			(layers "B.Cu" "B.Mask" "B.Paste")
			(net "SATA6G_PCH_PCIE_UP_SATA_TXN<1>")
		)
		(zone
			(layer "B.Cu")
			(hatch none 0.5)
			(connect_pads
				(clearance 0)
			)
			(min_thickness 0.25)
			(keepout
				(tracks allowed)
				(vias not_allowed)
				(pads allowed)
				(copperpour not_allowed)
				(footprints allowed)
			)
			(placement
				(enabled no)
				(sheetname "")
			)
			(fill
				(thermal_gap 0.5)
				(thermal_bridge_width 0.5)
				(island_removal_mode 0)
			)
			(polygon
				(pts
					(xy 421.767 -141.7066) (xy 421.259 -141.7066) (xy 421.259 -141.3256) (xy 421.767 -141.3256)
				)
			)
		)
		(zone
			(layer "B.Cu")
			(hatch none 0.5)
			(connect_pads
				(clearance 0)
			)
			(min_thickness 0.25)
			(keepout
				(tracks not_allowed)
				(vias allowed)
				(pads allowed)
				(copperpour not_allowed)
				(footprints allowed)
			)
			(placement
				(enabled no)
				(sheetname "")
			)
			(fill
				(thermal_gap 0.5)
				(thermal_bridge_width 0.5)
				(island_removal_mode 0)
			)
			(polygon
				(pts
					(xy 421.767 -141.3256) (xy 421.259 -141.3256) (xy 421.259 -141.7066) (xy 421.767 -141.7066)
				)
			)
		)
	)
	(footprint ""
		(layer "B.Cu")
		(at 383.73685 -111.85525 180)
		(property "Reference" "C3N3"
			(at 0 0 0)
			(layer "B.SilkS")
			(hide yes)
			(effects
				(font
					(size 1.27 1.27)
				)
				(justify mirror)
			)
		)
		(property "Value" ""
			(at 0 0 0)
			(layer "B.Fab")
			(effects
				(font
					(size 1.27 1.27)
				)
				(justify mirror)
			)
		)
		(duplicate_pad_numbers_are_jumpers no)
		(fp_rect
			(start 0.2794 0.9144)
			(end -0.2794 -0.1143)
			(stroke
				(width 0)
				(type default)
			)
			(fill no)
			(layer "B.CrtYd")
		)
		(fp_line
			(start 0.2794 0.9144)
			(end 0.2794 -0.1143)
			(stroke
				(width 0.1)
				(type default)
			)
			(layer "B.Fab")
		)
		(fp_line
			(start 0.2794 -0.1143)
			(end -0.2794 -0.1143)
			(stroke
				(width 0.1)
				(type default)
			)
			(layer "B.Fab")
		)
		(fp_line
			(start -0.2794 0.9144)
			(end 0.2794 0.9144)
			(stroke
				(width 0.1)
				(type default)
			)
			(layer "B.Fab")
		)
		(fp_line
			(start -0.2794 -0.1143)
			(end -0.2794 0.9144)
			(stroke
				(width 0.1)
				(type default)
			)
			(layer "B.Fab")
		)
		(pad "1" smd custom
			(at 0 0 90)
			(size 0.10414 0.10414)
			(layers "B.Cu" "B.Mask" "B.Paste")
			(net "PVNN_PCH_STBY")
			(options
				(clearance outline)
				(anchor circle)
			)
			(primitives
				(gr_poly
					(pts
						(xy -0.20828 -0.08636) (xy -0.20828 0.08636) (xy -0.08636 0.20828) (xy 0.086614 0.20828) (xy 0.20828 0.086614)
						(xy 0.20828 -0.08636) (xy 0.08636 -0.20828) (xy -0.08636 -0.20828)
					)
					(width 0)
					(fill yes)
				)
			)
		)
		(pad "2" smd custom
			(at 0 0.8001 90)
			(size 0.10414 0.10414)
			(layers "B.Cu" "B.Mask" "B.Paste")
			(net "GND")
			(options
				(clearance outline)
				(anchor circle)
			)
			(primitives
				(gr_poly
					(pts
						(xy -0.20828 -0.08636) (xy -0.20828 0.08636) (xy -0.08636 0.20828) (xy 0.086614 0.20828) (xy 0.20828 0.086614)
						(xy 0.20828 -0.08636) (xy 0.08636 -0.20828) (xy -0.08636 -0.20828)
					)
					(width 0)
					(fill yes)
				)
			)
		)
		(zone
			(layer "B.Cu")
			(hatch none 0.5)
			(connect_pads
				(clearance 0)
			)
			(min_thickness 0.25)
			(keepout
				(tracks allowed)
				(vias not_allowed)
				(pads allowed)
				(copperpour not_allowed)
				(footprints allowed)
			)
			(placement
				(enabled no)
				(sheetname "")
			)
			(fill
				(thermal_gap 0.5)
				(thermal_bridge_width 0.5)
				(island_removal_mode 0)
			)
			(polygon
				(pts
					(xy 383.64922 -112.0648) (xy 383.64922 -112.4458) (xy 383.82448 -112.4458) (xy 383.824734 -112.0648)
				)
			)
		)
		(zone
			(layer "B.Cu")
			(hatch none 0.5)
			(connect_pads
				(clearance 0)
			)
			(min_thickness 0.25)
			(keepout
				(tracks not_allowed)
				(vias allowed)
				(pads allowed)
				(copperpour not_allowed)
				(footprints allowed)
			)
			(placement
				(enabled no)
				(sheetname "")
			)
			(fill
				(thermal_gap 0.5)
				(thermal_bridge_width 0.5)
				(island_removal_mode 0)
			)
			(polygon
				(pts
					(xy 383.64922 -112.0648) (xy 383.64922 -112.4458) (xy 383.82448 -112.4458) (xy 383.824734 -112.0648)
				)
			)
		)
	)
	(footprint ""
		(layer "B.Cu")
		(at 413.0294 -94.0308 180)
		(property "Reference" "R7G7"
			(at 0 0 0)
			(layer "B.SilkS")
			(hide yes)
			(effects
				(font
					(size 1.27 1.27)
				)
				(justify mirror)
			)
		)
		(property "Value" ""
			(at 0 0 0)
			(layer "B.Fab")
			(effects
				(font
					(size 1.27 1.27)
				)
				(justify mirror)
			)
		)
		(duplicate_pad_numbers_are_jumpers no)
		(fp_poly
			(pts
				(xy 0.2794 -0.1016) (xy -0.2794 -0.1016) (xy -0.2794 0.9906) (xy 0.2794 0.9906)
			)
			(stroke
				(width 0)
				(type default)
			)
			(fill no)
			(layer "B.CrtYd")
		)
		(fp_line
			(start 0.2794 0.9906)
			(end -0.2794 0.9906)
			(stroke
				(width 0.1)
				(type default)
			)
			(layer "B.Fab")
		)
		(fp_line
			(start 0.2794 -0.1016)
			(end 0.2794 0.9906)
			(stroke
				(width 0.1)
				(type default)
			)
			(layer "B.Fab")
		)
		(fp_line
			(start -0.2794 0.9906)
			(end -0.2794 -0.1016)
			(stroke
				(width 0.1)
				(type default)
			)
			(layer "B.Fab")
		)
		(fp_line
			(start -0.2794 -0.1016)
			(end 0.2794 -0.1016)
			(stroke
				(width 0.1)
				(type default)
			)
			(layer "B.Fab")
		)
		(pad "1" smd rect
			(at 0 0)
			(size 0.508 0.508)
			(layers "B.Cu" "B.Mask" "B.Paste")
			(net "P3V3")
		)
		(pad "2" smd rect
			(at 0 0.889)
			(size 0.508 0.508)
			(layers "B.Cu" "B.Mask" "B.Paste")
			(net "H_CPU0_MEMABC_MEMHOT")
		)
		(zone
			(layer "B.Cu")
			(hatch none 0.5)
			(connect_pads
				(clearance 0)
			)
			(min_thickness 0.25)
			(keepout
				(tracks not_allowed)
				(vias allowed)
				(pads allowed)
				(copperpour not_allowed)
				(footprints allowed)
			)
			(placement
				(enabled no)
				(sheetname "")
			)
			(fill
				(thermal_gap 0.5)
				(thermal_bridge_width 0.5)
				(island_removal_mode 0)
			)
			(polygon
				(pts
					(xy 412.7754 -94.6658) (xy 413.2834 -94.6658) (xy 413.2834 -94.2848) (xy 412.7754 -94.2848)
				)
			)
		)
		(zone
			(layer "B.Cu")
			(hatch none 0.5)
			(connect_pads
				(clearance 0)
			)
			(min_thickness 0.25)
			(keepout
				(tracks allowed)
				(vias not_allowed)
				(pads allowed)
				(copperpour not_allowed)
				(footprints allowed)
			)
			(placement
				(enabled no)
				(sheetname "")
			)
			(fill
				(thermal_gap 0.5)
				(thermal_bridge_width 0.5)
				(island_removal_mode 0)
			)
			(polygon
				(pts
					(xy 412.7754 -94.2848) (xy 413.2834 -94.2848) (xy 413.2834 -94.6658) (xy 412.7754 -94.6658)
				)
			)
		)
	)
	(footprint ""
		(layer "B.Cu")
		(at -3.0861 -14.08684 -90)
		(property "Reference" "C22W3"
			(at 0 0 90)
			(layer "B.SilkS")
			(hide yes)
			(effects
				(font
					(size 1.27 1.27)
				)
				(justify mirror)
			)
		)
		(property "Value" "*"
			(at 0.0762 -6.2357 270)
			(unlocked yes)
			(layer "B.Fab")
			(hide yes)
			(effects
				(font
					(size 1.27 1.016)
					(thickness 0.1524)
				)
				(justify mirror)
			)
		)
		(property "Device Type" "SC22U16V5MX-4-GP_SMD-BCG5-SC22A"
			(at 0.0762 -8.2677 270)
			(unlocked yes)
			(layer "B.Fab")
			(hide yes)
			(effects
				(font
					(size 1.27 1.016)
					(thickness 0.1524)
				)
				(justify mirror)
			)
		)
		(duplicate_pad_numbers_are_jumpers no)
		(fp_line
			(start -0.635 0)
			(end 0.635 0)
			(stroke
				(width 0.508)
				(type default)
			)
			(layer "B.SilkS")
		)
		(fp_rect
			(start 0.9652 1.778)
			(end -0.9652 -1.778)
			(stroke
				(width 0)
				(type default)
			)
			(fill no)
			(layer "B.CrtYd")
		)
		(fp_poly
			(pts
				(xy 0.9652 -1.778) (xy -0.9652 -1.778) (xy -0.9652 1.778) (xy 0.9652 1.778)
			)
			(stroke
				(width 0)
				(type default)
			)
			(fill no)
			(layer "B.Fab")
		)
		(pad "1" smd rect
			(at 0 -0.9652 90)
			(size 1.397 1.143)
			(layers "B.Cu" "B.Mask" "B.Paste")
			(net "VR_FET_SW_P12V_STBY_PVDDQ_GHJ")
		)
		(pad "2" smd rect
			(at 0 0.9652 90)
			(size 1.397 1.143)
			(layers "B.Cu" "B.Mask" "B.Paste")
			(net "GND")
		)
	)
	(footprint ""
		(layer "B.Cu")
		(at 399.737834 -25.690068 90)
		(property "Reference" "R1U47"
			(at 0 0 90)
			(layer "B.SilkS")
			(hide yes)
			(effects
				(font
					(size 1.27 1.27)
				)
				(justify mirror)
			)
		)
		(property "Value" ""
			(at 0 0 90)
			(layer "B.Fab")
			(effects
				(font
					(size 1.27 1.27)
				)
				(justify mirror)
			)
		)
		(duplicate_pad_numbers_are_jumpers no)
		(fp_poly
			(pts
				(xy 0.2794 -0.1016) (xy -0.2794 -0.1016) (xy -0.2794 0.9906) (xy 0.2794 0.9906)
			)
			(stroke
				(width 0)
				(type default)
			)
			(fill no)
			(layer "B.CrtYd")
		)
		(fp_line
			(start 0.2794 -0.1016)
			(end 0.2794 0.9906)
			(stroke
				(width 0.1)
				(type default)
			)
			(layer "B.Fab")
		)
		(fp_line
			(start -0.2794 -0.1016)
			(end 0.2794 -0.1016)
			(stroke
				(width 0.1)
				(type default)
			)
			(layer "B.Fab")
		)
		(fp_line
			(start 0.2794 0.9906)
			(end -0.2794 0.9906)
			(stroke
				(width 0.1)
				(type default)
			)
			(layer "B.Fab")
		)
		(fp_line
			(start -0.2794 0.9906)
			(end -0.2794 -0.1016)
			(stroke
				(width 0.1)
				(type default)
			)
			(layer "B.Fab")
		)
		(pad "1" smd rect
			(at 0 0 270)
			(size 0.508 0.508)
			(layers "B.Cu" "B.Mask" "B.Paste")
			(net "P5V_STBY")
		)
		(pad "2" smd rect
			(at 0 0.889 270)
			(size 0.508 0.508)
			(layers "B.Cu" "B.Mask" "B.Paste")
			(net "A_P5V_STBY_SCALED")
		)
		(zone
			(layer "B.Cu")
			(hatch none 0.5)
			(connect_pads
				(clearance 0)
			)
			(min_thickness 0.25)
			(keepout
				(tracks allowed)
				(vias not_allowed)
				(pads allowed)
				(copperpour not_allowed)
				(footprints allowed)
			)
			(placement
				(enabled no)
				(sheetname "")
			)
			(fill
				(thermal_gap 0.5)
				(thermal_bridge_width 0.5)
				(island_removal_mode 0)
			)
			(polygon
				(pts
					(xy 399.991834 -25.944068) (xy 399.991834 -25.436068) (xy 400.372834 -25.436068) (xy 400.372834 -25.944068)
				)
			)
		)
		(zone
			(layer "B.Cu")
			(hatch none 0.5)
			(connect_pads
				(clearance 0)
			)
			(min_thickness 0.25)
			(keepout
				(tracks not_allowed)
				(vias allowed)
				(pads allowed)
				(copperpour not_allowed)
				(footprints allowed)
			)
			(placement
				(enabled no)
				(sheetname "")
			)
			(fill
				(thermal_gap 0.5)
				(thermal_bridge_width 0.5)
				(island_removal_mode 0)
			)
			(polygon
				(pts
					(xy 400.372834 -25.944068) (xy 400.372834 -25.436068) (xy 399.991834 -25.436068) (xy 399.991834 -25.944068)
				)
			)
		)
	)
)
